(kicad_pcb
	(version 20240108)
	(generator "pcbnew")
	(generator_version "8.0")
	(general
		(thickness 1.62)
		(legacy_teardrops no)
	)
	(paper "A4")
	(title_block
		(title "Jetson Orin Baseboard")
		(date "2025-03-12")
		(rev "1.3.4")
		(company "Antmicro Ltd")
		(comment 1 "www.antmicro.com")
		(comment 9 "footprints 85-89 of 677")
	)
	(layers
		(0 "F.Cu" signal)
		(1 "In1.Cu" signal)
		(2 "In2.Cu" signal)
		(3 "In3.Cu" signal)
		(4 "In4.Cu" jumper)
		(5 "In5.Cu" signal)
		(6 "In6.Cu" signal)
		(31 "B.Cu" signal)
		(32 "B.Adhes" user "B.Adhesive")
		(33 "F.Adhes" user "F.Adhesive")
		(34 "B.Paste" user)
		(35 "F.Paste" user)
		(36 "B.SilkS" user "B.Silkscreen")
		(37 "F.SilkS" user "F.Silkscreen")
		(38 "B.Mask" user)
		(39 "F.Mask" user)
		(40 "Dwgs.User" user "User.Drawings")
		(41 "Cmts.User" user "User.Comments")
		(42 "Eco1.User" user "User.Eco1")
		(43 "Eco2.User" user "User.Eco2")
		(44 "Edge.Cuts" user)
		(45 "Margin" user)
		(46 "B.CrtYd" user "B.Courtyard")
		(47 "F.CrtYd" user "F.Courtyard")
		(48 "B.Fab" user)
		(49 "F.Fab" user)
	)
	(footprint "antmicro-footprints:R_0402_1005Metric"
		(layer "F.Cu")
		(at 129.3 91.25 180)
		(descr "Resistor SMD 0402")
		(tags "resistor SMD 0402")
		(property "Reference" "R20"
			(at 2.925 -0.4 180)
			(layer "F.SilkS")
			(effects
				(font
					(size 0.7 0.7)
					(thickness 0.15)
				)
				(justify left bottom)
			)
		)
		(property "Value" "R_0R_0402"
			(at 0 1.4 180)
			(layer "F.Fab")
			(effects
				(font
					(size 0.7 0.7)
					(thickness 0.15)
				)
				(justify left bottom)
			)
		)
		(property "Footprint" "antmicro-footprints:R_0402_1005Metric"
			(at 0 0 180)
			(layer "F.Fab")
			(hide yes)
			(effects
				(font
					(size 1.27 1.27)
					(thickness 0.15)
				)
			)
		)
		(property "Datasheet" "https://industrial.panasonic.com/cdbs/www-data/pdf/RDA0000/AOA0000C301.pdf"
			(at 0 0 180)
			(layer "F.Fab")
			(hide yes)
			(effects
				(font
					(size 1.27 1.27)
					(thickness 0.15)
				)
			)
		)
		(property "Author" "Antmicro"
			(at 258.6 182.5 0)
			(layer "F.Fab")
			(hide yes)
			(effects
				(font
					(size 1 1)
					(thickness 0.15)
				)
			)
		)
		(property "Current" "1A"
			(at 258.6 182.5 0)
			(layer "F.Fab")
			(hide yes)
			(effects
				(font
					(size 1 1)
					(thickness 0.15)
				)
			)
		)
		(property "License" "Apache-2.0"
			(at 258.6 182.5 0)
			(layer "F.Fab")
			(hide yes)
			(effects
				(font
					(size 1 1)
					(thickness 0.15)
				)
			)
		)
		(property "MPN" "ERJ2GE0R00X"
			(at 258.6 182.5 0)
			(layer "F.Fab")
			(hide yes)
			(effects
				(font
					(size 1 1)
					(thickness 0.15)
				)
			)
		)
		(property "Manufacturer" "Panasonic"
			(at 258.6 182.5 0)
			(layer "F.Fab")
			(hide yes)
			(effects
				(font
					(size 1 1)
					(thickness 0.15)
				)
			)
		)
		(property "Tolerance" ""
			(at 258.6 182.5 0)
			(layer "F.Fab")
			(hide yes)
			(effects
				(font
					(size 1 1)
					(thickness 0.15)
				)
			)
		)
		(property "Val" "0R"
			(at 258.6 182.5 0)
			(layer "F.Fab")
			(hide yes)
			(effects
				(font
					(size 1 1)
					(thickness 0.15)
				)
			)
		)
		(sheetname "M.2")
		(sheetfile "m-2.kicad_sch")
		(attr smd)
		(fp_rect
			(start -0.925 -0.47)
			(end 0.925 0.47)
			(stroke
				(width 0.05)
				(type default)
			)
			(fill none)
			(layer "F.CrtYd")
		)
		(fp_rect
			(start -0.5 -0.25)
			(end 0.5 0.25)
			(stroke
				(width 0.15)
				(type solid)
			)
			(fill none)
			(layer "F.Fab")
		)
		(fp_text user "${REFERENCE}"
			(at -0.95 3.168 180)
			(layer "F.Fab")
			(hide yes)
			(effects
				(font
					(size 0.7 0.7)
					(thickness 0.15)
				)
				(justify left bottom)
			)
		)
		(fp_text user "Author: Antmicro"
			(at -0.95 4.169 180)
			(layer "F.Fab")
			(hide yes)
			(effects
				(font
					(size 0.7 0.7)
					(thickness 0.15)
				)
				(justify left bottom)
			)
		)
		(fp_text user "License: Apache-2.0"
			(at -0.95 5.169 180)
			(layer "F.Fab")
			(hide yes)
			(effects
				(font
					(size 0.7 0.7)
					(thickness 0.15)
				)
				(justify left bottom)
			)
		)
		(pad "1" smd roundrect
			(at -0.48 0 180)
			(size 0.59 0.64)
			(layers "F.Cu" "F.Paste" "F.Mask")
			(roundrect_rratio 0.25)
			(net 436 "USB1_D_P")
			(pintype "passive")
		)
		(pad "2" smd roundrect
			(at 0.48 0 180)
			(size 0.59 0.64)
			(layers "F.Cu" "F.Paste" "F.Mask")
			(roundrect_rratio 0.25)
			(net 616 "/M.2/USB_E_P")
			(pintype "passive")
		)
	)
	(footprint "antmicro-footprints:C_0402_1005Metric"
		(layer "F.Cu")
		(at 134.71 91.31 180)
		(descr "Capacitor SMD 0402")
		(tags "capacitor SMD 0402")
		(property "Reference" "C113"
			(at 3.785 -0.39 180)
			(layer "F.SilkS")
			(effects
				(font
					(size 0.7 0.7)
					(thickness 0.15)
				)
				(justify left bottom)
			)
		)
		(property "Value" "C_100n_0402"
			(at 0 1.4 180)
			(layer "F.Fab")
			(effects
				(font
					(size 0.7 0.7)
					(thickness 0.15)
				)
				(justify left bottom)
			)
		)
		(property "Footprint" "antmicro-footprints:C_0402_1005Metric"
			(at 0 0 180)
			(layer "F.Fab")
			(hide yes)
			(effects
				(font
					(size 1.27 1.27)
					(thickness 0.15)
				)
			)
		)
		(property "Datasheet" "https://www.murata.com/products/productdetail?partno=GRM155R61H104KE14%23"
			(at 0 0 180)
			(layer "F.Fab")
			(hide yes)
			(effects
				(font
					(size 1.27 1.27)
					(thickness 0.15)
				)
			)
		)
		(property "Author" "Antmicro"
			(at 269.42 182.62 0)
			(layer "F.Fab")
			(hide yes)
			(effects
				(font
					(size 1 1)
					(thickness 0.15)
				)
			)
		)
		(property "Dielectric" "X5R"
			(at 269.42 182.62 0)
			(layer "F.Fab")
			(hide yes)
			(effects
				(font
					(size 1 1)
					(thickness 0.15)
				)
			)
		)
		(property "License" "Apache-2.0"
			(at 269.42 182.62 0)
			(layer "F.Fab")
			(hide yes)
			(effects
				(font
					(size 1 1)
					(thickness 0.15)
				)
			)
		)
		(property "MPN" "GRM155R61H104KE14D"
			(at 269.42 182.62 0)
			(layer "F.Fab")
			(hide yes)
			(effects
				(font
					(size 1 1)
					(thickness 0.15)
				)
			)
		)
		(property "Manufacturer" "Murata"
			(at 269.42 182.62 0)
			(layer "F.Fab")
			(hide yes)
			(effects
				(font
					(size 1 1)
					(thickness 0.15)
				)
			)
		)
		(property "Val" "100n"
			(at 269.42 182.62 0)
			(layer "F.Fab")
			(hide yes)
			(effects
				(font
					(size 1 1)
					(thickness 0.15)
				)
			)
		)
		(property "Voltage" "50V"
			(at 269.42 182.62 0)
			(layer "F.Fab")
			(hide yes)
			(effects
				(font
					(size 1 1)
					(thickness 0.15)
				)
			)
		)
		(sheetname "Peripherals")
		(sheetfile "peripherals.kicad_sch")
		(attr smd)
		(fp_rect
			(start -0.925 -0.47)
			(end 0.925 0.47)
			(stroke
				(width 0.05)
				(type default)
			)
			(fill none)
			(layer "F.CrtYd")
		)
		(fp_line
			(start 0.504 0.248)
			(end -0.494 0.248)
			(stroke
				(width 0.15)
				(type solid)
			)
			(layer "F.Fab")
		)
		(fp_line
			(start 0.504 -0.25)
			(end 0.504 0.248)
			(stroke
				(width 0.15)
				(type solid)
			)
			(layer "F.Fab")
		)
		(fp_line
			(start -0.494 0.248)
			(end -0.494 -0.25)
			(stroke
				(width 0.15)
				(type solid)
			)
			(layer "F.Fab")
		)
		(fp_line
			(start -0.494 -0.25)
			(end 0.504 -0.25)
			(stroke
				(width 0.15)
				(type solid)
			)
			(layer "F.Fab")
		)
		(fp_text user "${REFERENCE}"
			(at -0.932 3.168 180)
			(layer "F.Fab")
			(hide yes)
			(effects
				(font
					(size 0.7 0.7)
					(thickness 0.15)
				)
				(justify left bottom)
			)
		)
		(fp_text user "Author: Antmicro"
			(at -0.932 4.17 180)
			(layer "F.Fab")
			(hide yes)
			(effects
				(font
					(size 0.7 0.7)
					(thickness 0.15)
				)
				(justify left bottom)
			)
		)
		(fp_text user "License: Apache-2.0"
			(at -0.932 5.17 180)
			(layer "F.Fab")
			(hide yes)
			(effects
				(font
					(size 0.7 0.7)
					(thickness 0.15)
				)
				(justify left bottom)
			)
		)
		(pad "1" smd roundrect
			(at -0.48 0 180)
			(size 0.59 0.64)
			(layers "F.Cu" "F.Paste" "F.Mask")
			(roundrect_rratio 0.25)
			(net 416 "/Peripherals/USBSS2_TX_CONN_N")
			(pintype "passive")
		)
		(pad "2" smd roundrect
			(at 0.48 0 180)
			(size 0.59 0.64)
			(layers "F.Cu" "F.Paste" "F.Mask")
			(roundrect_rratio 0.25)
			(net 132 "USBSS1_TX_N")
			(pintype "passive")
		)
	)
	(footprint "antmicro-footprints:R_0402_1005Metric"
		(layer "F.Cu")
		(at 114.4 98)
		(descr "Resistor SMD 0402")
		(tags "resistor SMD 0402")
		(property "Reference" "R27"
			(at -3.95 -1.125 0)
			(layer "F.SilkS")
			(effects
				(font
					(size 0.7 0.7)
					(thickness 0.15)
				)
				(justify left bottom)
			)
		)
		(property "Value" "R_47k_0402"
			(at 0 1.4 0)
			(layer "F.Fab")
			(effects
				(font
					(size 0.7 0.7)
					(thickness 0.15)
				)
				(justify left bottom)
			)
		)
		(property "Footprint" "antmicro-footprints:R_0402_1005Metric"
			(at 0 0 0)
			(layer "F.Fab")
			(hide yes)
			(effects
				(font
					(size 1.27 1.27)
					(thickness 0.15)
				)
			)
		)
		(property "Datasheet" "https://www.bourns.com/docs/product-datasheets/cr.pdf"
			(at 0 0 0)
			(layer "F.Fab")
			(hide yes)
			(effects
				(font
					(size 1.27 1.27)
					(thickness 0.15)
				)
			)
		)
		(property "Author" "Antmicro"
			(at 0 0 0)
			(layer "F.Fab")
			(hide yes)
			(effects
				(font
					(size 1 1)
					(thickness 0.15)
				)
			)
		)
		(property "License" "Apache-2.0"
			(at 0 0 0)
			(layer "F.Fab")
			(hide yes)
			(effects
				(font
					(size 1 1)
					(thickness 0.15)
				)
			)
		)
		(property "MPN" "CR0402-FX-4702GLF"
			(at 0 0 0)
			(layer "F.Fab")
			(hide yes)
			(effects
				(font
					(size 1 1)
					(thickness 0.15)
				)
			)
		)
		(property "Manufacturer" "Bourns"
			(at 0 0 0)
			(layer "F.Fab")
			(hide yes)
			(effects
				(font
					(size 1 1)
					(thickness 0.15)
				)
			)
		)
		(property "Tolerance" "1%"
			(at 0 0 0)
			(layer "F.Fab")
			(hide yes)
			(effects
				(font
					(size 1 1)
					(thickness 0.15)
				)
			)
		)
		(property "Val" "47k"
			(at 0 0 0)
			(layer "F.Fab")
			(hide yes)
			(effects
				(font
					(size 1 1)
					(thickness 0.15)
				)
			)
		)
		(sheetname "M.2")
		(sheetfile "m-2.kicad_sch")
		(attr smd exclude_from_pos_files exclude_from_bom dnp)
		(fp_rect
			(start -0.925 -0.47)
			(end 0.925 0.47)
			(stroke
				(width 0.05)
				(type default)
			)
			(fill none)
			(layer "F.CrtYd")
		)
		(fp_rect
			(start -0.5 -0.25)
			(end 0.5 0.25)
			(stroke
				(width 0.15)
				(type solid)
			)
			(fill none)
			(layer "F.Fab")
		)
		(fp_text user "Author: Antmicro"
			(at -0.95 4.169 0)
			(layer "F.Fab")
			(hide yes)
			(effects
				(font
					(size 0.7 0.7)
					(thickness 0.15)
				)
				(justify left bottom)
			)
		)
		(fp_text user "License: Apache-2.0"
			(at -0.95 5.169 0)
			(layer "F.Fab")
			(hide yes)
			(effects
				(font
					(size 0.7 0.7)
					(thickness 0.15)
				)
				(justify left bottom)
			)
		)
		(fp_text user "${REFERENCE}"
			(at -0.95 3.168 0)
			(layer "F.Fab")
			(hide yes)
			(effects
				(font
					(size 0.7 0.7)
					(thickness 0.15)
				)
				(justify left bottom)
			)
		)
		(pad "1" smd roundrect
			(at -0.48 0)
			(size 0.59 0.64)
			(layers "F.Cu" "F.Paste" "F.Mask")
			(roundrect_rratio 0.25)
			(net 87 "+3V3")
			(pintype "passive")
		)
		(pad "2" smd roundrect
			(at 0.48 0)
			(size 0.59 0.64)
			(layers "F.Cu" "F.Paste" "F.Mask")
			(roundrect_rratio 0.25)
			(net 65 "PCIE1_RST*")
			(pintype "passive")
		)
	)
	(footprint "antmicro-footprints:R_0402_1005Metric"
		(layer "F.Cu")
		(at 139.1 108.6)
		(descr "Resistor SMD 0402")
		(tags "resistor SMD 0402")
		(property "Reference" "R62"
			(at -3.075 0 0)
			(layer "F.SilkS")
			(effects
				(font
					(size 0.7 0.7)
					(thickness 0.15)
				)
				(justify left bottom)
			)
		)
		(property "Value" "R_0R_0402"
			(at 0 1.4 0)
			(layer "F.Fab")
			(effects
				(font
					(size 0.7 0.7)
					(thickness 0.15)
				)
				(justify left bottom)
			)
		)
		(property "Footprint" "antmicro-footprints:R_0402_1005Metric"
			(at 0 0 0)
			(layer "F.Fab")
			(hide yes)
			(effects
				(font
					(size 1.27 1.27)
					(thickness 0.15)
				)
			)
		)
		(property "Datasheet" "https://industrial.panasonic.com/cdbs/www-data/pdf/RDA0000/AOA0000C301.pdf"
			(at 0 0 0)
			(layer "F.Fab")
			(hide yes)
			(effects
				(font
					(size 1.27 1.27)
					(thickness 0.15)
				)
			)
		)
		(property "Author" "Antmicro"
			(at 0 0 0)
			(layer "F.Fab")
			(hide yes)
			(effects
				(font
					(size 1 1)
					(thickness 0.15)
				)
			)
		)
		(property "Current" "1A"
			(at 0 0 0)
			(layer "F.Fab")
			(hide yes)
			(effects
				(font
					(size 1 1)
					(thickness 0.15)
				)
			)
		)
		(property "License" "Apache-2.0"
			(at 0 0 0)
			(layer "F.Fab")
			(hide yes)
			(effects
				(font
					(size 1 1)
					(thickness 0.15)
				)
			)
		)
		(property "MPN" "ERJ2GE0R00X"
			(at 0 0 0)
			(layer "F.Fab")
			(hide yes)
			(effects
				(font
					(size 1 1)
					(thickness 0.15)
				)
			)
		)
		(property "Manufacturer" "Panasonic"
			(at 0 0 0)
			(layer "F.Fab")
			(hide yes)
			(effects
				(font
					(size 1 1)
					(thickness 0.15)
				)
			)
		)
		(property "Tolerance" ""
			(at 0 0 0)
			(layer "F.Fab")
			(hide yes)
			(effects
				(font
					(size 1 1)
					(thickness 0.15)
				)
			)
		)
		(property "Val" "0R"
			(at 0 0 0)
			(layer "F.Fab")
			(hide yes)
			(effects
				(font
					(size 1 1)
					(thickness 0.15)
				)
			)
		)
		(sheetname "Peripherals")
		(sheetfile "peripherals.kicad_sch")
		(attr smd)
		(fp_rect
			(start -0.925 -0.47)
			(end 0.925 0.47)
			(stroke
				(width 0.05)
				(type default)
			)
			(fill none)
			(layer "F.CrtYd")
		)
		(fp_rect
			(start -0.5 -0.25)
			(end 0.5 0.25)
			(stroke
				(width 0.15)
				(type solid)
			)
			(fill none)
			(layer "F.Fab")
		)
		(fp_text user "Author: Antmicro"
			(at -0.95 4.169 0)
			(layer "F.Fab")
			(hide yes)
			(effects
				(font
					(size 0.7 0.7)
					(thickness 0.15)
				)
				(justify left bottom)
			)
		)
		(fp_text user "License: Apache-2.0"
			(at -0.95 5.169 0)
			(layer "F.Fab")
			(hide yes)
			(effects
				(font
					(size 0.7 0.7)
					(thickness 0.15)
				)
				(justify left bottom)
			)
		)
		(fp_text user "${REFERENCE}"
			(at -0.95 3.168 0)
			(layer "F.Fab")
			(hide yes)
			(effects
				(font
					(size 0.7 0.7)
					(thickness 0.15)
				)
				(justify left bottom)
			)
		)
		(pad "1" smd roundrect
			(at -0.48 0)
			(size 0.59 0.64)
			(layers "F.Cu" "F.Paste" "F.Mask")
			(roundrect_rratio 0.25)
			(net 252 "SYS_SCL")
			(pintype "passive")
		)
		(pad "2" smd roundrect
			(at 0.48 0)
			(size 0.59 0.64)
			(layers "F.Cu" "F.Paste" "F.Mask")
			(roundrect_rratio 0.25)
			(net 598 "Net-(J11-Pad65)")
			(pintype "passive")
		)
	)
	(footprint "antmicro-footprints:C_0402_1005Metric"
		(layer "F.Cu")
		(at 81.9 105.6 180)
		(descr "Capacitor SMD 0402")
		(tags "capacitor SMD 0402")
		(property "Reference" "C141"
			(at -0.8 -0.45 180)
			(layer "F.SilkS")
			(effects
				(font
					(size 0.7 0.7)
					(thickness 0.15)
				)
				(justify left bottom)
			)
		)
		(property "Value" "C_100n_0402"
			(at 0 1.4 180)
			(layer "F.Fab")
			(effects
				(font
					(size 0.7 0.7)
					(thickness 0.15)
				)
				(justify left bottom)
			)
		)
		(property "Footprint" "antmicro-footprints:C_0402_1005Metric"
			(at 0 0 180)
			(layer "F.Fab")
			(hide yes)
			(effects
				(font
					(size 1.27 1.27)
					(thickness 0.15)
				)
			)
		)
		(property "Datasheet" "https://www.murata.com/products/productdetail?partno=GRM155R61H104KE14%23"
			(at 0 0 180)
			(layer "F.Fab")
			(hide yes)
			(effects
				(font
					(size 1.27 1.27)
					(thickness 0.15)
				)
			)
		)
		(property "Author" "Antmicro"
			(at 163.8 211.2 0)
			(layer "F.Fab")
			(hide yes)
			(effects
				(font
					(size 1 1)
					(thickness 0.15)
				)
			)
		)
		(property "Dielectric" "X5R"
			(at 163.8 211.2 0)
			(layer "F.Fab")
			(hide yes)
			(effects
				(font
					(size 1 1)
					(thickness 0.15)
				)
			)
		)
		(property "License" "Apache-2.0"
			(at 163.8 211.2 0)
			(layer "F.Fab")
			(hide yes)
			(effects
				(font
					(size 1 1)
					(thickness 0.15)
				)
			)
		)
		(property "MPN" "GRM155R61H104KE14D"
			(at 163.8 211.2 0)
			(layer "F.Fab")
			(hide yes)
			(effects
				(font
					(size 1 1)
					(thickness 0.15)
				)
			)
		)
		(property "Manufacturer" "Murata"
			(at 163.8 211.2 0)
			(layer "F.Fab")
			(hide yes)
			(effects
				(font
					(size 1 1)
					(thickness 0.15)
				)
			)
		)
		(property "Val" "100n"
			(at 163.8 211.2 0)
			(layer "F.Fab")
			(hide yes)
			(effects
				(font
					(size 1 1)
					(thickness 0.15)
				)
			)
		)
		(property "Voltage" "50V"
			(at 163.8 211.2 0)
			(layer "F.Fab")
			(hide yes)
			(effects
				(font
					(size 1 1)
					(thickness 0.15)
				)
			)
		)
		(sheetname "USB Debug, DP")
		(sheetfile "usb.kicad_sch")
		(attr smd)
		(fp_rect
			(start -0.925 -0.47)
			(end 0.925 0.47)
			(stroke
				(width 0.05)
				(type default)
			)
			(fill none)
			(layer "F.CrtYd")
		)
		(fp_line
			(start 0.504 0.248)
			(end -0.494 0.248)
			(stroke
				(width 0.15)
				(type solid)
			)
			(layer "F.Fab")
		)
		(fp_line
			(start 0.504 -0.25)
			(end 0.504 0.248)
			(stroke
				(width 0.15)
				(type solid)
			)
			(layer "F.Fab")
		)
		(fp_line
			(start -0.494 0.248)
			(end -0.494 -0.25)
			(stroke
				(width 0.15)
				(type solid)
			)
			(layer "F.Fab")
		)
		(fp_line
			(start -0.494 -0.25)
			(end 0.504 -0.25)
			(stroke
				(width 0.15)
				(type solid)
			)
			(layer "F.Fab")
		)
		(fp_text user "Author: Antmicro"
			(at -0.932 4.17 180)
			(layer "F.Fab")
			(hide yes)
			(effects
				(font
					(size 0.7 0.7)
					(thickness 0.15)
				)
				(justify left bottom)
			)
		)
		(fp_text user "${REFERENCE}"
			(at -0.932 3.168 180)
			(layer "F.Fab")
			(hide yes)
			(effects
				(font
					(size 0.7 0.7)
					(thickness 0.15)
				)
				(justify left bottom)
			)
		)
		(fp_text user "License: Apache-2.0"
			(at -0.932 5.17 180)
			(layer "F.Fab")
			(hide yes)
			(effects
				(font
					(size 0.7 0.7)
					(thickness 0.15)
				)
				(justify left bottom)
			)
		)
		(pad "1" smd roundrect
			(at -0.48 0 180)
			(size 0.59 0.64)
			(layers "F.Cu" "F.Paste" "F.Mask")
			(roundrect_rratio 0.25)
			(net 449 "USBSS0_TX_P")
			(pintype "passive")
		)
		(pad "2" smd roundrect
			(at 0.48 0 180)
			(size 0.59 0.64)
			(layers "F.Cu" "F.Paste" "F.Mask")
			(roundrect_rratio 0.25)
			(net 187 "/USB Debug, DP/USBSS0_TX_C_N")
			(pintype "passive")
		)
	)
)
